(kicad_pcb
	(version 20260206)
	(generator "pcbnew")
	(generator_version "10.0")
	(general
		(thickness 1.6)
		(legacy_teardrops no)
	)
	(paper "A4")
	(title_block
		(title "04192023_DAF0TMB3IC0_F0TG_MB_C_brd_V02_OCP.brd")
		(comment 1 "Grand Teton / footprints 1345-1350 of 8354")
	)
	(layers
		(0 "F.Cu" signal "TOP")
		(4 "In1.Cu" signal "GND")
		(6 "In2.Cu" signal "IN1")
		(8 "In3.Cu" signal "GND1")
		(10 "In4.Cu" signal "IN2")
		(12 "In5.Cu" signal "GND2")
		(14 "In6.Cu" signal "IN3")
		(16 "In7.Cu" signal "GND3")
		(18 "In8.Cu" signal "VCC")
		(20 "In9.Cu" signal "VCC1")
		(22 "In10.Cu" signal "GND4")
		(24 "In11.Cu" signal "IN4")
		(26 "In12.Cu" signal "GND5")
		(28 "In13.Cu" signal "IN5")
		(30 "In14.Cu" signal "GND6")
		(32 "In15.Cu" signal "IN6")
		(34 "In16.Cu" signal "GND7")
		(2 "B.Cu" signal "BOTTOM")
		(9 "F.Adhes" user "F.Adhesive")
		(11 "B.Adhes" user "B.Adhesive")
		(13 "F.Paste" user "Package Geometry/Pastemask Top")
		(15 "B.Paste" user "Package Geometry/Pastemask Bottom")
		(5 "F.SilkS" user "Ref Des/Silkscreen Top")
		(7 "B.SilkS" user "Ref Des/Silkscreen Bottom")
		(1 "F.Mask" user "Board Geometry/Soldermask Top")
		(3 "B.Mask" user "Board Geometry/Soldermask Bottom")
		(17 "Dwgs.User" user "User.Drawings")
		(19 "Cmts.User" user "User.Comments")
		(21 "Eco1.User" user "User.Eco1")
		(23 "Eco2.User" user "User.Eco2")
		(25 "Edge.Cuts" user "Board Geometry/Outline")
		(27 "Margin" user)
		(31 "F.CrtYd" user "Package Geometry/Place Bound Top")
		(29 "B.CrtYd" user "Package Geometry/Place Bound Bottom")
		(35 "F.Fab" user "Ref Des/Assembly Top")
		(33 "B.Fab" user "Ref Des/Assembly Bottom")
	)
	(footprint ""
		(layer "F.Cu")
		(at 246.04726 -418.118544 -90)
		(property "Reference" "PD15"
			(at -1.40208 3.638804 90)
			(unlocked yes)
			(layer "F.SilkS")
			(effects
				(font
					(size 0.7874 0.5842)
					(thickness 0.1524)
				)
				(justify left)
			)
		)
		(property "Value" ""
			(at 0 0 270)
			(layer "F.Fab")
			(effects
				(font
					(size 1.27 1.27)
				)
			)
		)
		(duplicate_pad_numbers_are_jumpers no)
		(fp_line
			(start -4.664456 3.109976)
			(end -4.664456 -3.109976)
			(stroke
				(width 0.1524)
				(type default)
			)
			(layer "F.SilkS")
		)
		(fp_line
			(start 4.156202 3.109976)
			(end 4.183126 3.109976)
			(stroke
				(width 0.1524)
				(type default)
			)
			(layer "F.SilkS")
		)
		(fp_line
			(start 4.743704 3.109976)
			(end 4.6101 3.109976)
			(stroke
				(width 0.1524)
				(type default)
			)
			(layer "F.SilkS")
		)
		(fp_line
			(start 4.743704 3.109976)
			(end 5.4102 3.109976)
			(stroke
				(width 0.1524)
				(type default)
			)
			(layer "F.SilkS")
		)
		(fp_line
			(start 4.769104 3.109976)
			(end -4.664456 3.109976)
			(stroke
				(width 0.1524)
				(type default)
			)
			(layer "F.SilkS")
		)
		(fp_line
			(start 4.794504 3.109976)
			(end 3.554984 3.109976)
			(stroke
				(width 0.1524)
				(type default)
			)
			(layer "F.SilkS")
		)
		(fp_line
			(start 5.4102 3.109976)
			(end 5.4102 -3.109976)
			(stroke
				(width 0.1524)
				(type default)
			)
			(layer "F.SilkS")
		)
		(fp_line
			(start 4.715002 3.035554)
			(end 4.7117 2.984754)
			(stroke
				(width 0.1524)
				(type default)
			)
			(layer "F.SilkS")
		)
		(fp_line
			(start 0.762 1.27)
			(end 0.762 -1.27)
			(stroke
				(width 0.1524)
				(type default)
			)
			(layer "F.SilkS")
		)
		(fp_line
			(start -0.508 1.016)
			(end -0.508 -1.016)
			(stroke
				(width 0.1524)
				(type default)
			)
			(layer "F.SilkS")
		)
		(fp_line
			(start -1.0668 0)
			(end -0.6096 0)
			(stroke
				(width 0.1524)
				(type default)
			)
			(layer "F.SilkS")
		)
		(fp_line
			(start 0.762 0)
			(end -0.508 1.016)
			(stroke
				(width 0.1524)
				(type default)
			)
			(layer "F.SilkS")
		)
		(fp_line
			(start 0.762 0)
			(end 1.2192 0)
			(stroke
				(width 0.1524)
				(type default)
			)
			(layer "F.SilkS")
		)
		(fp_line
			(start -0.508 -1.016)
			(end 0.762 0)
			(stroke
				(width 0.1524)
				(type default)
			)
			(layer "F.SilkS")
		)
		(fp_line
			(start -4.664456 -3.109976)
			(end 4.743704 -3.109976)
			(stroke
				(width 0.1524)
				(type default)
			)
			(layer "F.SilkS")
		)
		(fp_line
			(start 4.183126 -3.109976)
			(end 4.794504 -3.109976)
			(stroke
				(width 0.1524)
				(type default)
			)
			(layer "F.SilkS")
		)
		(fp_line
			(start 4.511802 -3.109976)
			(end 4.207002 -3.109976)
			(stroke
				(width 0.1524)
				(type default)
			)
			(layer "F.SilkS")
		)
		(fp_line
			(start 4.6101 -3.109976)
			(end 4.283202 -3.109976)
			(stroke
				(width 0.1524)
				(type default)
			)
			(layer "F.SilkS")
		)
		(fp_line
			(start 4.695444 -3.109976)
			(end 4.695444 3.109976)
			(stroke
				(width 0.1524)
				(type default)
			)
			(layer "F.SilkS")
		)
		(fp_line
			(start 4.70535 -3.109976)
			(end 4.70535 3.109976)
			(stroke
				(width 0.1524)
				(type default)
			)
			(layer "F.SilkS")
		)
		(fp_line
			(start 4.70535 -3.109976)
			(end 4.70535 3.109976)
			(stroke
				(width 0.1524)
				(type default)
			)
			(layer "F.SilkS")
		)
		(fp_line
			(start 4.70535 -3.109976)
			(end 4.70535 3.109976)
			(stroke
				(width 0.1524)
				(type default)
			)
			(layer "F.SilkS")
		)
		(fp_line
			(start 4.805426 -3.109976)
			(end 4.805426 3.109976)
			(stroke
				(width 0.1524)
				(type default)
			)
			(layer "F.SilkS")
		)
		(fp_line
			(start 4.932426 -3.109976)
			(end 4.932426 3.109976)
			(stroke
				(width 0.1524)
				(type default)
			)
			(layer "F.SilkS")
		)
		(fp_line
			(start 5.008626 -3.109976)
			(end 5.008626 3.109976)
			(stroke
				(width 0.1524)
				(type default)
			)
			(layer "F.SilkS")
		)
		(fp_line
			(start 5.110226 -3.109976)
			(end 5.110226 3.109976)
			(stroke
				(width 0.1524)
				(type default)
			)
			(layer "F.SilkS")
		)
		(fp_line
			(start 5.211826 -3.109976)
			(end 5.211826 3.109976)
			(stroke
				(width 0.1524)
				(type default)
			)
			(layer "F.SilkS")
		)
		(fp_line
			(start 5.262626 -3.109976)
			(end 5.262626 3.109976)
			(stroke
				(width 0.1524)
				(type default)
			)
			(layer "F.SilkS")
		)
		(fp_line
			(start 5.313426 -3.109976)
			(end 5.313426 3.109976)
			(stroke
				(width 0.1524)
				(type default)
			)
			(layer "F.SilkS")
		)
		(fp_line
			(start 5.4102 -3.109976)
			(end 4.783074 -3.109976)
			(stroke
				(width 0.1524)
				(type default)
			)
			(layer "F.SilkS")
		)
		(fp_line
			(start -4.065016 3.109976)
			(end -4.065016 -3.109976)
			(stroke
				(width 0.1)
				(type default)
			)
			(layer "F.Fab")
		)
		(fp_line
			(start 4.065016 3.109976)
			(end -4.065016 3.109976)
			(stroke
				(width 0.1)
				(type default)
			)
			(layer "F.Fab")
		)
		(fp_line
			(start -4.065016 -3.109976)
			(end 4.065016 -3.109976)
			(stroke
				(width 0.1)
				(type default)
			)
			(layer "F.Fab")
		)
		(fp_line
			(start 4.065016 -3.109976)
			(end 4.065016 3.109976)
			(stroke
				(width 0.1)
				(type default)
			)
			(layer "F.Fab")
		)
		(fp_text user "-"
			(at 6.643624 0.40005 90)
			(unlocked yes)
			(layer "F.SilkS")
			(effects
				(font
					(size 1.905 1.4224)
					(thickness 0.1524)
				)
				(justify left)
			)
		)
		(fp_text user "+"
			(at -4.5974 0.24765 90)
			(unlocked yes)
			(layer "F.SilkS")
			(effects
				(font
					(size 1.905 1.4224)
					(thickness 0.1524)
				)
				(justify left)
			)
		)
		(fp_text user "-"
			(at 6.643624 0.40005 90)
			(unlocked yes)
			(layer "F.Fab")
			(effects
				(font
					(size 1.905 1.4224)
					(thickness 0.1524)
				)
				(justify left)
			)
		)
		(fp_text user "+"
			(at -4.5974 0.24765 90)
			(unlocked yes)
			(layer "F.Fab")
			(effects
				(font
					(size 1.905 1.4224)
					(thickness 0.1524)
				)
				(justify left)
			)
		)
		(pad "A" smd rect
			(at -3.299968 0 90)
			(size 2.413 3.302)
			(layers "F.Cu" "F.Mask" "F.Paste")
			(net "GND")
		)
		(pad "C" smd rect
			(at 3.299968 0 90)
			(size 2.413 3.302)
			(layers "F.Cu" "F.Mask" "F.Paste")
			(net "P12V_PSU_FUSE")
		)
	)
	(footprint ""
		(layer "F.Cu")
		(at 49.778666 -25.309068 90)
		(property "Reference" "R3203"
			(at 0 0 90)
			(layer "F.SilkS")
			(hide yes)
			(effects
				(font
					(size 1.27 1.27)
				)
			)
		)
		(property "Value" ""
			(at 0 0 90)
			(layer "F.Fab")
			(effects
				(font
					(size 1.27 1.27)
				)
			)
		)
		(duplicate_pad_numbers_are_jumpers no)
		(fp_line
			(start 0.7874 -0.4064)
			(end 0.7874 0.4064)
			(stroke
				(width 0.1524)
				(type default)
			)
			(layer "F.SilkS")
		)
		(fp_line
			(start -0.7874 -0.4064)
			(end 0.7874 -0.4064)
			(stroke
				(width 0.1524)
				(type default)
			)
			(layer "F.SilkS")
		)
		(fp_line
			(start 0.7874 0.4064)
			(end -0.7874 0.4064)
			(stroke
				(width 0.1524)
				(type default)
			)
			(layer "F.SilkS")
		)
		(fp_line
			(start -0.7874 0.4064)
			(end -0.7874 -0.4064)
			(stroke
				(width 0.1524)
				(type default)
			)
			(layer "F.SilkS")
		)
		(fp_line
			(start -0.12065 -0.305054)
			(end -0.12065 -0.2794)
			(stroke
				(width 0.1)
				(type default)
			)
			(layer "F.Fab")
		)
		(fp_line
			(start -0.67945 -0.305054)
			(end -0.12065 -0.305054)
			(stroke
				(width 0.1)
				(type default)
			)
			(layer "F.Fab")
		)
		(fp_line
			(start 0.67945 -0.3048)
			(end 0.67945 0.3048)
			(stroke
				(width 0.1)
				(type default)
			)
			(layer "F.Fab")
		)
		(fp_line
			(start 0.12065 -0.3048)
			(end 0.67945 -0.3048)
			(stroke
				(width 0.1)
				(type default)
			)
			(layer "F.Fab")
		)
		(fp_line
			(start 0.12065 -0.2794)
			(end 0.12065 -0.3048)
			(stroke
				(width 0.1)
				(type default)
			)
			(layer "F.Fab")
		)
		(fp_line
			(start -0.12065 -0.2794)
			(end 0.12065 -0.2794)
			(stroke
				(width 0.1)
				(type default)
			)
			(layer "F.Fab")
		)
		(fp_line
			(start 0.120396 0.2794)
			(end -0.12065 0.2794)
			(stroke
				(width 0.1)
				(type default)
			)
			(layer "F.Fab")
		)
		(fp_line
			(start -0.12065 0.2794)
			(end -0.12065 0.3048)
			(stroke
				(width 0.1)
				(type default)
			)
			(layer "F.Fab")
		)
		(fp_line
			(start 0.67945 0.3048)
			(end 0.120396 0.3048)
			(stroke
				(width 0.1)
				(type default)
			)
			(layer "F.Fab")
		)
		(fp_line
			(start 0.120396 0.3048)
			(end 0.120396 0.2794)
			(stroke
				(width 0.1)
				(type default)
			)
			(layer "F.Fab")
		)
		(fp_line
			(start -0.12065 0.3048)
			(end -0.67945 0.3048)
			(stroke
				(width 0.1)
				(type default)
			)
			(layer "F.Fab")
		)
		(fp_line
			(start -0.67945 0.3048)
			(end -0.67945 -0.305054)
			(stroke
				(width 0.1)
				(type default)
			)
			(layer "F.Fab")
		)
		(pad "1" smd circle
			(at -0.40005 0 90)
			(size 0 0)
			(layers "F.Cu" "F.Mask" "F.Paste")
			(net "OCP_V3_2_AUX_PWR_EN")
		)
		(pad "2" smd circle
			(at 0.40005 0 90)
			(size 0 0)
			(layers "F.Cu" "F.Mask" "F.Paste")
			(net "OCP_V3_2_AUX_PWR_EN_R1")
		)
	)
	(footprint ""
		(layer "F.Cu")
		(at 148.971 -118.364 -90)
		(property "Reference" "R9021"
			(at 0 0 270)
			(layer "F.SilkS")
			(hide yes)
			(effects
				(font
					(size 1.27 1.27)
				)
			)
		)
		(property "Value" ""
			(at 0 0 270)
			(layer "F.Fab")
			(effects
				(font
					(size 1.27 1.27)
				)
			)
		)
		(duplicate_pad_numbers_are_jumpers no)
		(fp_line
			(start -0.7874 0.4064)
			(end -0.7874 -0.4064)
			(stroke
				(width 0.1524)
				(type default)
			)
			(layer "F.SilkS")
		)
		(fp_line
			(start 0.7874 0.4064)
			(end -0.7874 0.4064)
			(stroke
				(width 0.1524)
				(type default)
			)
			(layer "F.SilkS")
		)
		(fp_line
			(start -0.7874 -0.4064)
			(end 0.7874 -0.4064)
			(stroke
				(width 0.1524)
				(type default)
			)
			(layer "F.SilkS")
		)
		(fp_line
			(start 0.7874 -0.4064)
			(end 0.7874 0.4064)
			(stroke
				(width 0.1524)
				(type default)
			)
			(layer "F.SilkS")
		)
		(fp_line
			(start -0.67945 0.3048)
			(end -0.67945 -0.305054)
			(stroke
				(width 0.1)
				(type default)
			)
			(layer "F.Fab")
		)
		(fp_line
			(start -0.12065 0.3048)
			(end -0.67945 0.3048)
			(stroke
				(width 0.1)
				(type default)
			)
			(layer "F.Fab")
		)
		(fp_line
			(start 0.120396 0.3048)
			(end 0.120396 0.2794)
			(stroke
				(width 0.1)
				(type default)
			)
			(layer "F.Fab")
		)
		(fp_line
			(start 0.67945 0.3048)
			(end 0.120396 0.3048)
			(stroke
				(width 0.1)
				(type default)
			)
			(layer "F.Fab")
		)
		(fp_line
			(start -0.12065 0.2794)
			(end -0.12065 0.3048)
			(stroke
				(width 0.1)
				(type default)
			)
			(layer "F.Fab")
		)
		(fp_line
			(start 0.120396 0.2794)
			(end -0.12065 0.2794)
			(stroke
				(width 0.1)
				(type default)
			)
			(layer "F.Fab")
		)
		(fp_line
			(start -0.12065 -0.2794)
			(end 0.12065 -0.2794)
			(stroke
				(width 0.1)
				(type default)
			)
			(layer "F.Fab")
		)
		(fp_line
			(start 0.12065 -0.2794)
			(end 0.12065 -0.3048)
			(stroke
				(width 0.1)
				(type default)
			)
			(layer "F.Fab")
		)
		(fp_line
			(start 0.12065 -0.3048)
			(end 0.67945 -0.3048)
			(stroke
				(width 0.1)
				(type default)
			)
			(layer "F.Fab")
		)
		(fp_line
			(start 0.67945 -0.3048)
			(end 0.67945 0.3048)
			(stroke
				(width 0.1)
				(type default)
			)
			(layer "F.Fab")
		)
		(fp_line
			(start -0.67945 -0.305054)
			(end -0.12065 -0.305054)
			(stroke
				(width 0.1)
				(type default)
			)
			(layer "F.Fab")
		)
		(fp_line
			(start -0.12065 -0.305054)
			(end -0.12065 -0.2794)
			(stroke
				(width 0.1)
				(type default)
			)
			(layer "F.Fab")
		)
		(pad "1" smd circle
			(at -0.40005 0 270)
			(size 0 0)
			(layers "F.Cu" "F.Mask" "F.Paste")
			(net "P12V_AUX")
		)
		(pad "2" smd circle
			(at 0.40005 0 270)
			(size 0 0)
			(layers "F.Cu" "F.Mask" "F.Paste")
			(net "U206_VS")
		)
	)
	(footprint ""
		(layer "F.Cu")
		(at 74.357738 -401.884388 90)
		(property "Reference" "C7007"
			(at 0 0 90)
			(layer "F.SilkS")
			(hide yes)
			(effects
				(font
					(size 1.27 1.27)
				)
			)
		)
		(property "Value" ""
			(at 0 0 90)
			(layer "F.Fab")
			(effects
				(font
					(size 1.27 1.27)
				)
			)
		)
		(duplicate_pad_numbers_are_jumpers no)
		(fp_line
			(start 1.524 -0.762)
			(end 1.524 0.762)
			(stroke
				(width 0.1524)
				(type default)
			)
			(layer "F.SilkS")
		)
		(fp_line
			(start -1.524 -0.762)
			(end 1.524 -0.762)
			(stroke
				(width 0.1524)
				(type default)
			)
			(layer "F.SilkS")
		)
		(fp_line
			(start 1.524 0.762)
			(end -1.524 0.762)
			(stroke
				(width 0.1524)
				(type default)
			)
			(layer "F.SilkS")
		)
		(fp_line
			(start -1.524 0.762)
			(end -1.524 -0.762)
			(stroke
				(width 0.1524)
				(type default)
			)
			(layer "F.SilkS")
		)
		(fp_line
			(start 1.1049 -0.724916)
			(end -1.1049 -0.724916)
			(stroke
				(width 0.1)
				(type default)
			)
			(layer "F.Fab")
		)
		(fp_line
			(start -1.1049 -0.724916)
			(end -1.1049 0.724916)
			(stroke
				(width 0.1)
				(type default)
			)
			(layer "F.Fab")
		)
		(fp_line
			(start 1.1049 0.724916)
			(end 1.1049 -0.724916)
			(stroke
				(width 0.1)
				(type default)
			)
			(layer "F.Fab")
		)
		(fp_line
			(start -1.1049 0.724916)
			(end 1.1049 0.724916)
			(stroke
				(width 0.1)
				(type default)
			)
			(layer "F.Fab")
		)
		(pad "1" smd rect
			(at -0.889 0 270)
			(size 1.016 1.27)
			(layers "F.Cu" "F.Mask" "F.Paste")
			(net "P0V9_CPU1_RT_2D")
		)
		(pad "2" smd rect
			(at 0.889 0 270)
			(size 1.016 1.27)
			(layers "F.Cu" "F.Mask" "F.Paste")
			(net "GND")
		)
	)
	(footprint ""
		(layer "F.Cu")
		(at 177.748946 -413.815022 90)
		(property "Reference" "R2693"
			(at 0 0 90)
			(layer "F.SilkS")
			(hide yes)
			(effects
				(font
					(size 1.27 1.27)
				)
			)
		)
		(property "Value" ""
			(at 0 0 90)
			(layer "F.Fab")
			(effects
				(font
					(size 1.27 1.27)
				)
			)
		)
		(duplicate_pad_numbers_are_jumpers no)
		(fp_line
			(start 0.7874 -0.4064)
			(end 0.7874 0.4064)
			(stroke
				(width 0.1524)
				(type default)
			)
			(layer "F.SilkS")
		)
		(fp_line
			(start -0.7874 -0.4064)
			(end 0.7874 -0.4064)
			(stroke
				(width 0.1524)
				(type default)
			)
			(layer "F.SilkS")
		)
		(fp_line
			(start 0.7874 0.4064)
			(end -0.7874 0.4064)
			(stroke
				(width 0.1524)
				(type default)
			)
			(layer "F.SilkS")
		)
		(fp_line
			(start -0.7874 0.4064)
			(end -0.7874 -0.4064)
			(stroke
				(width 0.1524)
				(type default)
			)
			(layer "F.SilkS")
		)
		(fp_line
			(start -0.12065 -0.305054)
			(end -0.12065 -0.2794)
			(stroke
				(width 0.1)
				(type default)
			)
			(layer "F.Fab")
		)
		(fp_line
			(start -0.67945 -0.305054)
			(end -0.12065 -0.305054)
			(stroke
				(width 0.1)
				(type default)
			)
			(layer "F.Fab")
		)
		(fp_line
			(start 0.67945 -0.3048)
			(end 0.67945 0.3048)
			(stroke
				(width 0.1)
				(type default)
			)
			(layer "F.Fab")
		)
		(fp_line
			(start 0.12065 -0.3048)
			(end 0.67945 -0.3048)
			(stroke
				(width 0.1)
				(type default)
			)
			(layer "F.Fab")
		)
		(fp_line
			(start 0.12065 -0.2794)
			(end 0.12065 -0.3048)
			(stroke
				(width 0.1)
				(type default)
			)
			(layer "F.Fab")
		)
		(fp_line
			(start -0.12065 -0.2794)
			(end 0.12065 -0.2794)
			(stroke
				(width 0.1)
				(type default)
			)
			(layer "F.Fab")
		)
		(fp_line
			(start 0.120396 0.2794)
			(end -0.12065 0.2794)
			(stroke
				(width 0.1)
				(type default)
			)
			(layer "F.Fab")
		)
		(fp_line
			(start -0.12065 0.2794)
			(end -0.12065 0.3048)
			(stroke
				(width 0.1)
				(type default)
			)
			(layer "F.Fab")
		)
		(fp_line
			(start 0.67945 0.3048)
			(end 0.120396 0.3048)
			(stroke
				(width 0.1)
				(type default)
			)
			(layer "F.Fab")
		)
		(fp_line
			(start 0.120396 0.3048)
			(end 0.120396 0.2794)
			(stroke
				(width 0.1)
				(type default)
			)
			(layer "F.Fab")
		)
		(fp_line
			(start -0.12065 0.3048)
			(end -0.67945 0.3048)
			(stroke
				(width 0.1)
				(type default)
			)
			(layer "F.Fab")
		)
		(fp_line
			(start -0.67945 0.3048)
			(end -0.67945 -0.305054)
			(stroke
				(width 0.1)
				(type default)
			)
			(layer "F.Fab")
		)
		(pad "1" smd circle
			(at -0.40005 0 90)
			(size 0 0)
			(layers "F.Cu" "F.Mask" "F.Paste")
			(net "P3V3_AUX")
		)
		(pad "2" smd circle
			(at 0.40005 0 90)
			(size 0 0)
			(layers "F.Cu" "F.Mask" "F.Paste")
			(net "TCA9539_0_ADD1")
		)
	)
	(footprint ""
		(layer "F.Cu")
		(at 38.774878 -16.099536 90)
		(property "Reference" "C695"
			(at 0 0 90)
			(layer "F.SilkS")
			(hide yes)
			(effects
				(font
					(size 1.27 1.27)
				)
			)
		)
		(property "Value" ""
			(at 0 0 90)
			(layer "F.Fab")
			(effects
				(font
					(size 1.27 1.27)
				)
			)
		)
		(duplicate_pad_numbers_are_jumpers no)
		(fp_line
			(start 0.299974 -0.150114)
			(end 0.299974 0.150114)
			(stroke
				(width 0.1)
				(type default)
			)
			(layer "F.Fab")
		)
		(fp_line
			(start -0.299974 -0.150114)
			(end 0.299974 -0.150114)
			(stroke
				(width 0.1)
				(type default)
			)
			(layer "F.Fab")
		)
		(fp_line
			(start 0.299974 0.150114)
			(end -0.299974 0.150114)
			(stroke
				(width 0.1)
				(type default)
			)
			(layer "F.Fab")
		)
		(fp_line
			(start -0.299974 0.150114)
			(end -0.299974 -0.150114)
			(stroke
				(width 0.1)
				(type default)
			)
			(layer "F.Fab")
		)
		(pad "1" smd rect
			(at -0.2667 0 90)
			(size 0.3048 0.381)
			(layers "F.Cu" "F.Mask" "F.Paste")
			(net "P5E_CPU1_G1_TX_C_DP<7>")
		)
		(pad "2" smd rect
			(at 0.2667 0 90)
			(size 0.3048 0.381)
			(layers "F.Cu" "F.Mask" "F.Paste")
			(net "P5E_CPU1_G1_TX_DP<7>")
		)
	)
)
